(kicad_pcb
	(version 20260206)
	(generator "pcbnew")
	(generator_version "10.0")
	(general
		(thickness 1.6)
		(legacy_teardrops no)
	)
	(paper "A4")
	(title_block
		(title "03242023_DA0F0TMBIJ0_F0T_Motherboard_J_brd_V01_OCP.brd")
		(comment 1 "Grand Teton / footprints 3926-3932 of 6105")
	)
	(layers
		(0 "F.Cu" signal "TOP")
		(4 "In1.Cu" signal "GND")
		(6 "In2.Cu" signal "IN1")
		(8 "In3.Cu" signal "GND1")
		(10 "In4.Cu" signal "IN2")
		(12 "In5.Cu" signal "GND2")
		(14 "In6.Cu" signal "IN3")
		(16 "In7.Cu" signal "GND3")
		(18 "In8.Cu" signal "VCC")
		(20 "In9.Cu" signal "VCC1")
		(22 "In10.Cu" signal "GND4")
		(24 "In11.Cu" signal "IN4")
		(26 "In12.Cu" signal "GND5")
		(28 "In13.Cu" signal "IN5")
		(30 "In14.Cu" signal "GND6")
		(32 "In15.Cu" signal "IN6")
		(34 "In16.Cu" signal "GND7")
		(2 "B.Cu" signal "BOTTOM")
		(9 "F.Adhes" user "F.Adhesive")
		(11 "B.Adhes" user "B.Adhesive")
		(13 "F.Paste" user "Package Geometry/Pastemask Top")
		(15 "B.Paste" user "Package Geometry/Pastemask Bottom")
		(5 "F.SilkS" user "Ref Des/Silkscreen Top")
		(7 "B.SilkS" user "Ref Des/Silkscreen Bottom")
		(1 "F.Mask" user "Board Geometry/Soldermask Top")
		(3 "B.Mask" user "Board Geometry/Soldermask Bottom")
		(17 "Dwgs.User" user "User.Drawings")
		(19 "Cmts.User" user "User.Comments")
		(21 "Eco1.User" user "User.Eco1")
		(23 "Eco2.User" user "User.Eco2")
		(25 "Edge.Cuts" user "Board Geometry/Outline")
		(27 "Margin" user)
		(31 "F.CrtYd" user "Package Geometry/Place Bound Top")
		(29 "B.CrtYd" user "Package Geometry/Place Bound Bottom")
		(35 "F.Fab" user "Ref Des/Assembly Top")
		(33 "B.Fab" user "Ref Des/Assembly Bottom")
	)
	(footprint ""
		(layer "F.Cu")
		(at 15.436596 -387.119876 180)
		(property "Reference" "R3293"
			(at 0 0 180)
			(layer "F.SilkS")
			(hide yes)
			(effects
				(font
					(size 1.27 1.27)
				)
			)
		)
		(property "Value" ""
			(at 0 0 180)
			(layer "F.Fab")
			(effects
				(font
					(size 1.27 1.27)
				)
			)
		)
		(duplicate_pad_numbers_are_jumpers no)
		(fp_line
			(start 0.7874 0.4064)
			(end -0.7874 0.4064)
			(stroke
				(width 0.1524)
				(type default)
			)
			(layer "F.SilkS")
		)
		(fp_line
			(start 0.7874 -0.4064)
			(end 0.7874 0.4064)
			(stroke
				(width 0.1524)
				(type default)
			)
			(layer "F.SilkS")
		)
		(fp_line
			(start -0.7874 0.4064)
			(end -0.7874 -0.4064)
			(stroke
				(width 0.1524)
				(type default)
			)
			(layer "F.SilkS")
		)
		(fp_line
			(start -0.7874 -0.4064)
			(end 0.7874 -0.4064)
			(stroke
				(width 0.1524)
				(type default)
			)
			(layer "F.SilkS")
		)
		(fp_line
			(start 0.67945 0.3048)
			(end 0.120396 0.3048)
			(stroke
				(width 0.1)
				(type default)
			)
			(layer "F.Fab")
		)
		(fp_line
			(start 0.67945 -0.3048)
			(end 0.67945 0.3048)
			(stroke
				(width 0.1)
				(type default)
			)
			(layer "F.Fab")
		)
		(fp_line
			(start 0.12065 -0.2794)
			(end 0.12065 -0.3048)
			(stroke
				(width 0.1)
				(type default)
			)
			(layer "F.Fab")
		)
		(fp_line
			(start 0.12065 -0.3048)
			(end 0.67945 -0.3048)
			(stroke
				(width 0.1)
				(type default)
			)
			(layer "F.Fab")
		)
		(fp_line
			(start 0.120396 0.3048)
			(end 0.120396 0.2794)
			(stroke
				(width 0.1)
				(type default)
			)
			(layer "F.Fab")
		)
		(fp_line
			(start 0.120396 0.2794)
			(end -0.12065 0.2794)
			(stroke
				(width 0.1)
				(type default)
			)
			(layer "F.Fab")
		)
		(fp_line
			(start -0.12065 0.3048)
			(end -0.67945 0.3048)
			(stroke
				(width 0.1)
				(type default)
			)
			(layer "F.Fab")
		)
		(fp_line
			(start -0.12065 0.2794)
			(end -0.12065 0.3048)
			(stroke
				(width 0.1)
				(type default)
			)
			(layer "F.Fab")
		)
		(fp_line
			(start -0.12065 -0.2794)
			(end 0.12065 -0.2794)
			(stroke
				(width 0.1)
				(type default)
			)
			(layer "F.Fab")
		)
		(fp_line
			(start -0.12065 -0.305054)
			(end -0.12065 -0.2794)
			(stroke
				(width 0.1)
				(type default)
			)
			(layer "F.Fab")
		)
		(fp_line
			(start -0.67945 0.3048)
			(end -0.67945 -0.305054)
			(stroke
				(width 0.1)
				(type default)
			)
			(layer "F.Fab")
		)
		(fp_line
			(start -0.67945 -0.305054)
			(end -0.12065 -0.305054)
			(stroke
				(width 0.1)
				(type default)
			)
			(layer "F.Fab")
		)
		(pad "1" smd circle
			(at -0.40005 0 180)
			(size 0 0)
			(layers "F.Cu" "F.Mask" "F.Paste")
			(net "FM_P2E_MODE")
		)
		(pad "2" smd circle
			(at 0.40005 0 180)
			(size 0 0)
			(layers "F.Cu" "F.Mask" "F.Paste")
			(net "GND")
		)
	)
	(footprint ""
		(layer "F.Cu")
		(at 81.8896 -41.036748 180)
		(property "Reference" "C2347"
			(at 0 0 180)
			(layer "F.SilkS")
			(hide yes)
			(effects
				(font
					(size 1.27 1.27)
				)
			)
		)
		(property "Value" ""
			(at 0 0 180)
			(layer "F.Fab")
			(effects
				(font
					(size 1.27 1.27)
				)
			)
		)
		(duplicate_pad_numbers_are_jumpers no)
		(fp_line
			(start 0.7874 0.4064)
			(end -0.7874 0.4064)
			(stroke
				(width 0.1524)
				(type default)
			)
			(layer "F.SilkS")
		)
		(fp_line
			(start 0.7874 -0.4064)
			(end 0.7874 0.4064)
			(stroke
				(width 0.1524)
				(type default)
			)
			(layer "F.SilkS")
		)
		(fp_line
			(start -0.7874 0.4064)
			(end -0.7874 -0.4064)
			(stroke
				(width 0.1524)
				(type default)
			)
			(layer "F.SilkS")
		)
		(fp_line
			(start -0.7874 -0.4064)
			(end 0.7874 -0.4064)
			(stroke
				(width 0.1524)
				(type default)
			)
			(layer "F.SilkS")
		)
		(fp_line
			(start 0.67945 0.3048)
			(end 0.120396 0.3048)
			(stroke
				(width 0.1)
				(type default)
			)
			(layer "F.Fab")
		)
		(fp_line
			(start 0.67945 -0.3048)
			(end 0.67945 0.3048)
			(stroke
				(width 0.1)
				(type default)
			)
			(layer "F.Fab")
		)
		(fp_line
			(start 0.12065 -0.2794)
			(end 0.12065 -0.3048)
			(stroke
				(width 0.1)
				(type default)
			)
			(layer "F.Fab")
		)
		(fp_line
			(start 0.12065 -0.3048)
			(end 0.67945 -0.3048)
			(stroke
				(width 0.1)
				(type default)
			)
			(layer "F.Fab")
		)
		(fp_line
			(start 0.120396 0.3048)
			(end 0.120396 0.2794)
			(stroke
				(width 0.1)
				(type default)
			)
			(layer "F.Fab")
		)
		(fp_line
			(start 0.120396 0.2794)
			(end -0.12065 0.2794)
			(stroke
				(width 0.1)
				(type default)
			)
			(layer "F.Fab")
		)
		(fp_line
			(start -0.12065 0.3048)
			(end -0.67945 0.3048)
			(stroke
				(width 0.1)
				(type default)
			)
			(layer "F.Fab")
		)
		(fp_line
			(start -0.12065 0.2794)
			(end -0.12065 0.3048)
			(stroke
				(width 0.1)
				(type default)
			)
			(layer "F.Fab")
		)
		(fp_line
			(start -0.12065 -0.2794)
			(end 0.12065 -0.2794)
			(stroke
				(width 0.1)
				(type default)
			)
			(layer "F.Fab")
		)
		(fp_line
			(start -0.12065 -0.305054)
			(end -0.12065 -0.2794)
			(stroke
				(width 0.1)
				(type default)
			)
			(layer "F.Fab")
		)
		(fp_line
			(start -0.67945 0.3048)
			(end -0.67945 -0.305054)
			(stroke
				(width 0.1)
				(type default)
			)
			(layer "F.Fab")
		)
		(fp_line
			(start -0.67945 -0.305054)
			(end -0.12065 -0.305054)
			(stroke
				(width 0.1)
				(type default)
			)
			(layer "F.Fab")
		)
		(pad "1" smd circle
			(at -0.40005 0 180)
			(size 0 0)
			(layers "F.Cu" "F.Mask" "F.Paste")
			(net "P3V3_AUX")
		)
		(pad "2" smd circle
			(at 0.40005 0 180)
			(size 0 0)
			(layers "F.Cu" "F.Mask" "F.Paste")
			(net "GND")
		)
	)
	(footprint ""
		(layer "F.Cu")
		(at 299.02023 -50.336196)
		(property "Reference" "R2240"
			(at 0 0 0)
			(layer "F.SilkS")
			(hide yes)
			(effects
				(font
					(size 1.27 1.27)
				)
			)
		)
		(property "Value" ""
			(at 0 0 0)
			(layer "F.Fab")
			(effects
				(font
					(size 1.27 1.27)
				)
			)
		)
		(duplicate_pad_numbers_are_jumpers no)
		(fp_line
			(start -0.7874 -0.4064)
			(end 0.7874 -0.4064)
			(stroke
				(width 0.1524)
				(type default)
			)
			(layer "F.SilkS")
		)
		(fp_line
			(start -0.7874 0.4064)
			(end -0.7874 -0.4064)
			(stroke
				(width 0.1524)
				(type default)
			)
			(layer "F.SilkS")
		)
		(fp_line
			(start 0.7874 -0.4064)
			(end 0.7874 0.4064)
			(stroke
				(width 0.1524)
				(type default)
			)
			(layer "F.SilkS")
		)
		(fp_line
			(start 0.7874 0.4064)
			(end -0.7874 0.4064)
			(stroke
				(width 0.1524)
				(type default)
			)
			(layer "F.SilkS")
		)
		(fp_line
			(start -0.67945 -0.305054)
			(end -0.12065 -0.305054)
			(stroke
				(width 0.1)
				(type default)
			)
			(layer "F.Fab")
		)
		(fp_line
			(start -0.67945 0.3048)
			(end -0.67945 -0.305054)
			(stroke
				(width 0.1)
				(type default)
			)
			(layer "F.Fab")
		)
		(fp_line
			(start -0.12065 -0.305054)
			(end -0.12065 -0.2794)
			(stroke
				(width 0.1)
				(type default)
			)
			(layer "F.Fab")
		)
		(fp_line
			(start -0.12065 -0.2794)
			(end 0.12065 -0.2794)
			(stroke
				(width 0.1)
				(type default)
			)
			(layer "F.Fab")
		)
		(fp_line
			(start -0.12065 0.2794)
			(end -0.12065 0.3048)
			(stroke
				(width 0.1)
				(type default)
			)
			(layer "F.Fab")
		)
		(fp_line
			(start -0.12065 0.3048)
			(end -0.67945 0.3048)
			(stroke
				(width 0.1)
				(type default)
			)
			(layer "F.Fab")
		)
		(fp_line
			(start 0.120396 0.2794)
			(end -0.12065 0.2794)
			(stroke
				(width 0.1)
				(type default)
			)
			(layer "F.Fab")
		)
		(fp_line
			(start 0.120396 0.3048)
			(end 0.120396 0.2794)
			(stroke
				(width 0.1)
				(type default)
			)
			(layer "F.Fab")
		)
		(fp_line
			(start 0.12065 -0.3048)
			(end 0.67945 -0.3048)
			(stroke
				(width 0.1)
				(type default)
			)
			(layer "F.Fab")
		)
		(fp_line
			(start 0.12065 -0.2794)
			(end 0.12065 -0.3048)
			(stroke
				(width 0.1)
				(type default)
			)
			(layer "F.Fab")
		)
		(fp_line
			(start 0.67945 -0.3048)
			(end 0.67945 0.3048)
			(stroke
				(width 0.1)
				(type default)
			)
			(layer "F.Fab")
		)
		(fp_line
			(start 0.67945 0.3048)
			(end 0.120396 0.3048)
			(stroke
				(width 0.1)
				(type default)
			)
			(layer "F.Fab")
		)
		(pad "1" smd circle
			(at -0.40005 0)
			(size 0 0)
			(layers "F.Cu" "F.Mask" "F.Paste")
			(net "P1V05_PCH_AUX")
		)
		(pad "2" smd circle
			(at 0.40005 0)
			(size 0 0)
			(layers "F.Cu" "F.Mask" "F.Paste")
			(net "FM_BOARD_SKU_ID1")
		)
	)
	(footprint ""
		(layer "F.Cu")
		(at 346.465652 -315.66739 90)
		(property "Reference" "PC325"
			(at 0 0 90)
			(layer "F.SilkS")
			(hide yes)
			(effects
				(font
					(size 1.27 1.27)
				)
			)
		)
		(property "Value" ""
			(at 0 0 90)
			(layer "F.Fab")
			(effects
				(font
					(size 1.27 1.27)
				)
			)
		)
		(duplicate_pad_numbers_are_jumpers no)
		(fp_line
			(start 2.750058 0.999998)
			(end -2.750058 0.999998)
			(stroke
				(width 0.1524)
				(type default)
			)
			(layer "F.SilkS")
		)
		(fp_circle
			(center 0 0.999998)
			(end 0 3.750056)
			(stroke
				(width 0.1524)
				(type default)
			)
			(fill no)
			(layer "F.SilkS")
		)
		(fp_poly
			(pts
				(arc
					(start 2.750058 0.999998)
					(mid 0 3.750056)
					(end -2.750058 0.999998)
				)
			)
			(stroke
				(width 0)
				(type default)
			)
			(fill yes)
			(layer "F.SilkS")
		)
		(fp_circle
			(center 0 0.999998)
			(end 0 3.750056)
			(stroke
				(width 0.1)
				(type default)
			)
			(fill no)
			(layer "F.Fab")
		)
		(pad "1" thru_hole rect
			(at 0 0 90)
			(size 1.5748 1.5748)
			(drill 1.0668)
			(layers "*.Cu" "*.Mask")
			(remove_unused_layers no)
			(net "PVCCIN_CPU0")
			(clearance 0)
			(padstack
				(mode front_inner_back)
				(layer "Inner"
					(shape circle)
					(size 1.5748 1.5748)
					(clearance 0)
				)
				(layer "B.Cu"
					(shape rect)
					(size 1.5748 1.5748)
					(clearance 0)
				)
			)
		)
		(pad "2" thru_hole circle
			(at 0 1.999996 90)
			(size 1.5748 1.5748)
			(drill 1.0668)
			(layers "*.Cu" "*.Mask")
			(remove_unused_layers no)
			(net "GND")
			(clearance 0)
		)
	)
	(footprint ""
		(layer "F.Cu")
		(at 104.8258 -409.2702)
		(property "Reference" "R4727"
			(at 0 0 0)
			(layer "F.SilkS")
			(hide yes)
			(effects
				(font
					(size 1.27 1.27)
				)
			)
		)
		(property "Value" ""
			(at 0 0 0)
			(layer "F.Fab")
			(effects
				(font
					(size 1.27 1.27)
				)
			)
		)
		(duplicate_pad_numbers_are_jumpers no)
		(fp_line
			(start -0.7874 -0.4064)
			(end 0.7874 -0.4064)
			(stroke
				(width 0.1524)
				(type default)
			)
			(layer "F.SilkS")
		)
		(fp_line
			(start -0.7874 0.4064)
			(end -0.7874 -0.4064)
			(stroke
				(width 0.1524)
				(type default)
			)
			(layer "F.SilkS")
		)
		(fp_line
			(start 0.7874 -0.4064)
			(end 0.7874 0.4064)
			(stroke
				(width 0.1524)
				(type default)
			)
			(layer "F.SilkS")
		)
		(fp_line
			(start 0.7874 0.4064)
			(end -0.7874 0.4064)
			(stroke
				(width 0.1524)
				(type default)
			)
			(layer "F.SilkS")
		)
		(fp_line
			(start -0.67945 -0.305054)
			(end -0.12065 -0.305054)
			(stroke
				(width 0.1)
				(type default)
			)
			(layer "F.Fab")
		)
		(fp_line
			(start -0.67945 0.3048)
			(end -0.67945 -0.305054)
			(stroke
				(width 0.1)
				(type default)
			)
			(layer "F.Fab")
		)
		(fp_line
			(start -0.12065 -0.305054)
			(end -0.12065 -0.2794)
			(stroke
				(width 0.1)
				(type default)
			)
			(layer "F.Fab")
		)
		(fp_line
			(start -0.12065 -0.2794)
			(end 0.12065 -0.2794)
			(stroke
				(width 0.1)
				(type default)
			)
			(layer "F.Fab")
		)
		(fp_line
			(start -0.12065 0.2794)
			(end -0.12065 0.3048)
			(stroke
				(width 0.1)
				(type default)
			)
			(layer "F.Fab")
		)
		(fp_line
			(start -0.12065 0.3048)
			(end -0.67945 0.3048)
			(stroke
				(width 0.1)
				(type default)
			)
			(layer "F.Fab")
		)
		(fp_line
			(start 0.120396 0.2794)
			(end -0.12065 0.2794)
			(stroke
				(width 0.1)
				(type default)
			)
			(layer "F.Fab")
		)
		(fp_line
			(start 0.120396 0.3048)
			(end 0.120396 0.2794)
			(stroke
				(width 0.1)
				(type default)
			)
			(layer "F.Fab")
		)
		(fp_line
			(start 0.12065 -0.3048)
			(end 0.67945 -0.3048)
			(stroke
				(width 0.1)
				(type default)
			)
			(layer "F.Fab")
		)
		(fp_line
			(start 0.12065 -0.2794)
			(end 0.12065 -0.3048)
			(stroke
				(width 0.1)
				(type default)
			)
			(layer "F.Fab")
		)
		(fp_line
			(start 0.67945 -0.3048)
			(end 0.67945 0.3048)
			(stroke
				(width 0.1)
				(type default)
			)
			(layer "F.Fab")
		)
		(fp_line
			(start 0.67945 0.3048)
			(end 0.120396 0.3048)
			(stroke
				(width 0.1)
				(type default)
			)
			(layer "F.Fab")
		)
		(pad "1" smd circle
			(at -0.40005 0)
			(size 0 0)
			(layers "F.Cu" "F.Mask" "F.Paste")
			(net "P3V3_AUX")
		)
		(pad "2" smd circle
			(at 0.40005 0)
			(size 0 0)
			(layers "F.Cu" "F.Mask" "F.Paste")
			(net "PRSNT_SWB_N")
		)
	)
	(footprint ""
		(layer "F.Cu")
		(at 114.706654 -360.83875)
		(property "Reference" "PC548"
			(at 0 0 0)
			(layer "F.SilkS")
			(hide yes)
			(effects
				(font
					(size 1.27 1.27)
				)
			)
		)
		(property "Value" ""
			(at 0 0 0)
			(layer "F.Fab")
			(effects
				(font
					(size 1.27 1.27)
				)
			)
		)
		(duplicate_pad_numbers_are_jumpers no)
		(fp_line
			(start -0.7874 -0.4064)
			(end 0.7874 -0.4064)
			(stroke
				(width 0.1524)
				(type default)
			)
			(layer "F.SilkS")
		)
		(fp_line
			(start -0.7874 0.4064)
			(end -0.7874 -0.4064)
			(stroke
				(width 0.1524)
				(type default)
			)
			(layer "F.SilkS")
		)
		(fp_line
			(start 0.7874 -0.4064)
			(end 0.7874 0.4064)
			(stroke
				(width 0.1524)
				(type default)
			)
			(layer "F.SilkS")
		)
		(fp_line
			(start 0.7874 0.4064)
			(end -0.7874 0.4064)
			(stroke
				(width 0.1524)
				(type default)
			)
			(layer "F.SilkS")
		)
		(fp_line
			(start -0.67945 -0.305054)
			(end -0.12065 -0.305054)
			(stroke
				(width 0.1)
				(type default)
			)
			(layer "F.Fab")
		)
		(fp_line
			(start -0.67945 0.3048)
			(end -0.67945 -0.305054)
			(stroke
				(width 0.1)
				(type default)
			)
			(layer "F.Fab")
		)
		(fp_line
			(start -0.12065 -0.305054)
			(end -0.12065 -0.2794)
			(stroke
				(width 0.1)
				(type default)
			)
			(layer "F.Fab")
		)
		(fp_line
			(start -0.12065 -0.2794)
			(end 0.12065 -0.2794)
			(stroke
				(width 0.1)
				(type default)
			)
			(layer "F.Fab")
		)
		(fp_line
			(start -0.12065 0.2794)
			(end -0.12065 0.3048)
			(stroke
				(width 0.1)
				(type default)
			)
			(layer "F.Fab")
		)
		(fp_line
			(start -0.12065 0.3048)
			(end -0.67945 0.3048)
			(stroke
				(width 0.1)
				(type default)
			)
			(layer "F.Fab")
		)
		(fp_line
			(start 0.120396 0.2794)
			(end -0.12065 0.2794)
			(stroke
				(width 0.1)
				(type default)
			)
			(layer "F.Fab")
		)
		(fp_line
			(start 0.120396 0.3048)
			(end 0.120396 0.2794)
			(stroke
				(width 0.1)
				(type default)
			)
			(layer "F.Fab")
		)
		(fp_line
			(start 0.12065 -0.3048)
			(end 0.67945 -0.3048)
			(stroke
				(width 0.1)
				(type default)
			)
			(layer "F.Fab")
		)
		(fp_line
			(start 0.12065 -0.2794)
			(end 0.12065 -0.3048)
			(stroke
				(width 0.1)
				(type default)
			)
			(layer "F.Fab")
		)
		(fp_line
			(start 0.67945 -0.3048)
			(end 0.67945 0.3048)
			(stroke
				(width 0.1)
				(type default)
			)
			(layer "F.Fab")
		)
		(fp_line
			(start 0.67945 0.3048)
			(end 0.120396 0.3048)
			(stroke
				(width 0.1)
				(type default)
			)
			(layer "F.Fab")
		)
		(pad "1" smd circle
			(at -0.40005 0)
			(size 0 0)
			(layers "F.Cu" "F.Mask" "F.Paste")
			(net "PVCCIN_CPU1_VIN_CSNIN")
		)
		(pad "2" smd circle
			(at 0.40005 0)
			(size 0 0)
			(layers "F.Cu" "F.Mask" "F.Paste")
			(net "GND")
		)
	)
	(footprint ""
		(layer "F.Cu")
		(at 466.5345 -96.007682 -90)
		(property "Reference" "R1289"
			(at 0 0 270)
			(layer "F.SilkS")
			(hide yes)
			(effects
				(font
					(size 1.27 1.27)
				)
			)
		)
		(property "Value" ""
			(at 0 0 270)
			(layer "F.Fab")
			(effects
				(font
					(size 1.27 1.27)
				)
			)
		)
		(duplicate_pad_numbers_are_jumpers no)
		(fp_line
			(start -0.7874 0.4064)
			(end -0.7874 -0.4064)
			(stroke
				(width 0.1524)
				(type default)
			)
			(layer "F.SilkS")
		)
		(fp_line
			(start 0.7874 0.4064)
			(end -0.7874 0.4064)
			(stroke
				(width 0.1524)
				(type default)
			)
			(layer "F.SilkS")
		)
		(fp_line
			(start -0.7874 -0.4064)
			(end 0.7874 -0.4064)
			(stroke
				(width 0.1524)
				(type default)
			)
			(layer "F.SilkS")
		)
		(fp_line
			(start 0.7874 -0.4064)
			(end 0.7874 0.4064)
			(stroke
				(width 0.1524)
				(type default)
			)
			(layer "F.SilkS")
		)
		(fp_line
			(start -0.67945 0.3048)
			(end -0.67945 -0.305054)
			(stroke
				(width 0.1)
				(type default)
			)
			(layer "F.Fab")
		)
		(fp_line
			(start -0.12065 0.3048)
			(end -0.67945 0.3048)
			(stroke
				(width 0.1)
				(type default)
			)
			(layer "F.Fab")
		)
		(fp_line
			(start 0.120396 0.3048)
			(end 0.120396 0.2794)
			(stroke
				(width 0.1)
				(type default)
			)
			(layer "F.Fab")
		)
		(fp_line
			(start 0.67945 0.3048)
			(end 0.120396 0.3048)
			(stroke
				(width 0.1)
				(type default)
			)
			(layer "F.Fab")
		)
		(fp_line
			(start -0.12065 0.2794)
			(end -0.12065 0.3048)
			(stroke
				(width 0.1)
				(type default)
			)
			(layer "F.Fab")
		)
		(fp_line
			(start 0.120396 0.2794)
			(end -0.12065 0.2794)
			(stroke
				(width 0.1)
				(type default)
			)
			(layer "F.Fab")
		)
		(fp_line
			(start -0.12065 -0.2794)
			(end 0.12065 -0.2794)
			(stroke
				(width 0.1)
				(type default)
			)
			(layer "F.Fab")
		)
		(fp_line
			(start 0.12065 -0.2794)
			(end 0.12065 -0.3048)
			(stroke
				(width 0.1)
				(type default)
			)
			(layer "F.Fab")
		)
		(fp_line
			(start 0.12065 -0.3048)
			(end 0.67945 -0.3048)
			(stroke
				(width 0.1)
				(type default)
			)
			(layer "F.Fab")
		)
		(fp_line
			(start 0.67945 -0.3048)
			(end 0.67945 0.3048)
			(stroke
				(width 0.1)
				(type default)
			)
			(layer "F.Fab")
		)
		(fp_line
			(start -0.67945 -0.305054)
			(end -0.12065 -0.305054)
			(stroke
				(width 0.1)
				(type default)
			)
			(layer "F.Fab")
		)
		(fp_line
			(start -0.12065 -0.305054)
			(end -0.12065 -0.2794)
			(stroke
				(width 0.1)
				(type default)
			)
			(layer "F.Fab")
		)
		(pad "1" smd circle
			(at -0.40005 0 270)
			(size 0 0)
			(layers "F.Cu" "F.Mask" "F.Paste")
			(net "FB_BMC_ISOLATE")
		)
		(pad "2" smd circle
			(at 0.40005 0 270)
			(size 0 0)
			(layers "F.Cu" "F.Mask" "F.Paste")
			(net "GND")
		)
	)
)
